FILE_TYPE = CONNECTIVITY;
{Allegro Design Entry HDL 17.2-2016 S081 (4005846) 1/11/2022}
"PAGE_NUMBER" = 77;
0"NC";
1"GND\g";
2"GND\g";
3"GND\g";
4"GND\g";
5"GND\g";
6"GND\g";
7"PWRGD_CPU1_PWROK";
8"P1V8_STBY\g";
9"PWRGD_CPU0_PWROK";
10"P1V8_STBY\g";
11"PVDDCR_CPU1_P0_RESET_N";
12"PVDDCR_CPU0_P0_RESET_N";
13"PVDDCR_CPU0_P1_RESET_N";
14"PVDDCR_CPU1_P1_RESET_N";
%"Q_RES"
"2","(-5900,3950)","2","pure_quanta","I1";
;
LOCATION"R702"
$SEC"1"
CDS_SEC"1"
WATTAGE"1/16W"
MATERIAL"EMPTY"
TOLERANCE"5%"
VALUE"10K"
PART_NUMBER"TMP_QCS31002JB28"
PACK_TYPE"0402LF"
CDS_LIB"pure_quanta";
"A"
$PN"1"9;
"B"
$PN"2"2;
%"UNIVERSAL_GND"
"1","(-4125,4375)","0","pure_quanta_power","I10";
;
CDS_LIB"pure_quanta_power"
HDL_POWER"GND";
"A"1;
%"Q_CAP"
"1","(-4125,4575)","0","pure_quanta","I11";
;
LOCATION"C223"
$SEC"1"
CDS_SEC"1"
MATERIAL"X7R"
TOLERANCE"10%"
VALUE"0.1UF"
VOLTAGE"25V"
PACK_TYPE"0402"
CDS_LIB"pure_quanta"
PART_NUMBER"CH4104K1B00";
"B"
$PN"2"1;
"A"
$PN"1"10;
%"UNIVERSAL_POWER"
"1","(-4200,4900)","2","pure_quanta_power","I12";
;
HDL_POWER"P1V8_STBY"
CDS_LIB"pure_quanta_power";
"A"10;
%"SN74LVC2G07DCKR"
"1","(-4675,4275)","0","pure_quanta","I15";
;
LOCATION"U29"
$SEC"1"
CDS_SEC"1"
MATERIAL"IC"
VALUE"SN74LVC2G07DCKR"
PART_NUMBER"AL002G07006"
PACK_TYPE"SMLF"
NEEDS_NO_SIZE"TRUE"
CDS_LIB"pure_quanta";
"VCC"
$PN"5"10;
"GND"
$PN"2"6;
"2Y"
$PN"4"11;
"1Y"
$PN"6"12;
"2A"
$PN"3"9;
"1A"
$PN"1"9;
%"Q_CAP"
"1","(-4075,2800)","0","pure_quanta","I19";
;
LOCATION"C224"
$SEC"1"
CDS_SEC"1"
MATERIAL"X7R"
TOLERANCE"10%"
VALUE"0.1UF"
VOLTAGE"25V"
PACK_TYPE"0402"
CDS_LIB"pure_quanta"
PART_NUMBER"CH4104K1B00";
"B"
$PN"2"3;
"A"
$PN"1"8;
%"GND"
"1","(-5900,3675)","0","pure_quanta_power","I2";
;
CDS_LIB"pure_quanta_power"
SIZE"1B"
BOM_COST"MEM"
HDL_POWER"GND";
"A<SIZE-1..0>\NAC"2;
%"UNIVERSAL_GND"
"1","(-4075,2600)","0","pure_quanta_power","I20";
;
CDS_LIB"pure_quanta_power"
HDL_POWER"GND";
"A"3;
%"SN74LVC2G07DCKR"
"1","(-4625,2500)","0","pure_quanta","I21";
;
LOCATION"U40"
$SEC"1"
CDS_SEC"1"
MATERIAL"IC"
VALUE"SN74LVC2G07DCKR"
PART_NUMBER"AL002G07006"
PACK_TYPE"SMLF"
NEEDS_NO_SIZE"TRUE"
CDS_LIB"pure_quanta";
"VCC"
$PN"5"8;
"GND"
$PN"2"4;
"2Y"
$PN"4"14;
"1Y"
$PN"6"13;
"2A"
$PN"3"7;
"1A"
$PN"1"7;
%"UNIVERSAL_GND"
"1","(-5050,2500)","5","pure_quanta_power","I22";
;
CDS_LIB"pure_quanta_power"
HDL_POWER"GND";
"A"4;
%"UNIVERSAL_POWER"
"1","(-4150,3125)","2","pure_quanta_power","I23";
;
HDL_POWER"P1V8_STBY"
CDS_LIB"pure_quanta_power";
"A"8;
%"Q_RES"
"2","(-5850,2175)","2","pure_quanta","I5";
;
LOCATION"R703"
$SEC"1"
CDS_SEC"1"
WATTAGE"1/16W"
MATERIAL"EMPTY"
TOLERANCE"5%"
VALUE"10K"
PART_NUMBER"TMP_QCS31002JB28"
PACK_TYPE"0402LF"
CDS_LIB"pure_quanta";
"A"
$PN"1"7;
"B"
$PN"2"5;
%"GND"
"1","(-5850,1900)","0","pure_quanta_power","I6";
;
SIZE"1B"
BOM_COST"MEM"
CDS_LIB"pure_quanta_power"
HDL_POWER"GND";
"A<SIZE-1..0>\NAC"5;
%"UNIVERSAL_GND"
"1","(-5100,4275)","5","pure_quanta_power","I9";
;
CDS_LIB"pure_quanta_power"
HDL_POWER"GND";
"A"6;
END.
